# T6G (Grand Teton) — schematic netlist excerpt (pin names and nets, part order shuffled) for the footprints in the layout excerpt that follows; sources: Cadence DE-HDL packaged netlist, KiCad conversion of 04192023_DAF0TMB3IC0_F0TG_MB_C_brd_V02_OCP.brd

C61  Q_CAP  100NF 50V 10% X7R  pkg C0402  page 188 : A = P3V3 ; B = GND
J123  CONN1_10165288101LF  CONN1_10165288-101LF IO  pkg CON_GUIDE-F1XG  page 230 : NC1 = NC

(kicad_pcb
	(version 20260206)
	(generator "pcbnew")
	(generator_version "10.0")
	(general
		(thickness 1.6)
		(legacy_teardrops no)
	)
	(paper "A4")
	(title_block
		(title "04192023_DAF0TMB3IC0_F0TG_MB_C_brd_V02_OCP.brd")
		(comment 1 "Grand Teton / footprints 398-399 of 8354")
	)
	(layers
		(0 "F.Cu" signal "TOP")
		(4 "In1.Cu" signal "GND")
		(6 "In2.Cu" signal "IN1")
		(8 "In3.Cu" signal "GND1")
		(10 "In4.Cu" signal "IN2")
		(12 "In5.Cu" signal "GND2")
		(14 "In6.Cu" signal "IN3")
		(16 "In7.Cu" signal "GND3")
		(18 "In8.Cu" signal "VCC")
		(20 "In9.Cu" signal "VCC1")
		(22 "In10.Cu" signal "GND4")
		(24 "In11.Cu" signal "IN4")
		(26 "In12.Cu" signal "GND5")
		(28 "In13.Cu" signal "IN5")
		(30 "In14.Cu" signal "GND6")
		(32 "In15.Cu" signal "IN6")
		(34 "In16.Cu" signal "GND7")
		(2 "B.Cu" signal "BOTTOM")
		(9 "F.Adhes" user "F.Adhesive")
		(11 "B.Adhes" user "B.Adhesive")
		(13 "F.Paste" user "Package Geometry/Pastemask Top")
		(15 "B.Paste" user "Package Geometry/Pastemask Bottom")
		(5 "F.SilkS" user "Ref Des/Silkscreen Top")
		(7 "B.SilkS" user "Ref Des/Silkscreen Bottom")
		(1 "F.Mask" user "Board Geometry/Soldermask Top")
		(3 "B.Mask" user "Board Geometry/Soldermask Bottom")
		(17 "Dwgs.User" user "User.Drawings")
		(19 "Cmts.User" user "User.Comments")
		(21 "Eco1.User" user "User.Eco1")
		(23 "Eco2.User" user "User.Eco2")
		(25 "Edge.Cuts" user "Board Geometry/Outline")
		(27 "Margin" user)
		(31 "F.CrtYd" user "Package Geometry/Place Bound Top")
		(29 "B.CrtYd" user "Package Geometry/Place Bound Bottom")
		(35 "F.Fab" user "Ref Des/Assembly Top")
		(33 "B.Fab" user "Ref Des/Assembly Bottom")
	)
	(footprint ""
		(layer "F.Cu")
		(at 112.024922 -431.360072 180)
		(property "Reference" "J123"
			(at 1.199134 -11.256772 0)
			(unlocked yes)
			(layer "F.SilkS")
			(effects
				(font
					(size 0.7874 0.5842)
					(thickness 0.1524)
				)
				(justify left)
			)
		)
		(property "Value" ""
			(at 0 0 180)
			(layer "F.Fab")
			(effects
				(font
					(size 1.27 1.27)
				)
			)
		)
		(duplicate_pad_numbers_are_jumpers no)
		(fp_line
			(start 3.525012 9.614408)
			(end 3.525012 6.154928)
			(stroke
				(width 0.1524)
				(type default)
			)
			(layer "F.SilkS")
		)
		(fp_line
			(start 3.525012 2.344928)
			(end 3.525012 -10.489946)
			(stroke
				(width 0.1524)
				(type default)
			)
			(layer "F.SilkS")
		)
		(fp_line
			(start 3.525012 -10.489946)
			(end -3.525012 -10.489946)
			(stroke
				(width 0.1524)
				(type default)
			)
			(layer "F.SilkS")
		)
		(fp_line
			(start -3.525012 -10.489946)
			(end -3.525012 9.614408)
			(stroke
				(width 0.1524)
				(type default)
			)
			(layer "F.SilkS")
		)
		(fp_line
			(start 3.525012 21.310092)
			(end 3.525012 -10.489946)
			(stroke
				(width 0.1)
				(type default)
			)
			(layer "F.Fab")
		)
		(fp_line
			(start 3.525012 -10.489946)
			(end -3.525012 -10.489946)
			(stroke
				(width 0.1)
				(type default)
			)
			(layer "F.Fab")
		)
		(fp_line
			(start -3.525012 21.310092)
			(end 3.525012 21.310092)
			(stroke
				(width 0.1)
				(type default)
			)
			(layer "F.Fab")
		)
		(fp_line
			(start -3.525012 -10.489946)
			(end -3.525012 21.310092)
			(stroke
				(width 0.1)
				(type default)
			)
			(layer "F.Fab")
		)
		(pad "" np_thru_hole circle
			(at 0 -6.620002 180)
			(size 3.175 3.175)
			(drill 3.175)
			(layers "*.Cu" "*.Mask")
			(clearance 0.381)
			(thermal_gap 0.381)
		)
		(pad "" np_thru_hole circle
			(at 0 0 180)
			(size 0 0)
			(drill 3.175)
			(layers "*.Cu" "*.Mask")
			(clearance 0)
		)
		(pad "" np_thru_hole circle
			(at 0 5.130038 180)
			(size 3.175 3.175)
			(drill 3.175)
			(layers "*.Cu" "*.Mask")
			(clearance 0.381)
			(thermal_gap 0.381)
		)
		(zone
			(layers "F.Cu" "B.Cu" "In1.Cu" "In2.Cu" "In3.Cu" "In4.Cu" "In5.Cu" "In6.Cu"
				"In7.Cu" "In8.Cu" "In9.Cu" "In10.Cu" "In11.Cu" "In12.Cu" "In13.Cu" "In14.Cu"
				"In15.Cu" "In16.Cu"
			)
			(hatch none 0.5)
			(connect_pads
				(clearance 0)
			)
			(min_thickness 0.25)
			(keepout
				(tracks not_allowed)
				(vias allowed)
				(pads allowed)
				(copperpour not_allowed)
				(footprints allowed)
			)
			(placement
				(enabled no)
				(sheetname "")
			)
			(fill
				(thermal_gap 0.5)
				(thermal_bridge_width 0.5)
				(island_removal_mode 0)
			)
			(polygon
				(pts
					(arc
						(start 114.120422 -436.49011)
						(mid 109.929422 -436.49011)
						(end 114.120422 -436.49011)
					)
				)
			)
		)
		(zone
			(layers "F.Cu" "B.Cu" "In1.Cu" "In2.Cu" "In3.Cu" "In4.Cu" "In5.Cu" "In6.Cu"
				"In7.Cu" "In8.Cu" "In9.Cu" "In10.Cu" "In11.Cu" "In12.Cu" "In13.Cu" "In14.Cu"
				"In15.Cu" "In16.Cu"
			)
			(hatch none 0.5)
			(connect_pads
				(clearance 0)
			)
			(min_thickness 0.25)
			(keepout
				(tracks not_allowed)
				(vias allowed)
				(pads allowed)
				(copperpour not_allowed)
				(footprints allowed)
			)
			(placement
				(enabled no)
				(sheetname "")
			)
			(fill
				(thermal_gap 0.5)
				(thermal_bridge_width 0.5)
				(island_removal_mode 0)
			)
			(polygon
				(pts
					(arc
						(start 114.120422 -424.74007)
						(mid 109.929422 -424.74007)
						(end 114.120422 -424.74007)
					)
				)
			)
		)
		(zone
			(layers "F.Cu" "B.Cu" "In1.Cu" "In2.Cu" "In3.Cu" "In4.Cu" "In5.Cu" "In6.Cu"
				"In7.Cu" "In8.Cu" "In9.Cu" "In10.Cu" "In11.Cu" "In12.Cu" "In13.Cu" "In14.Cu"
				"In15.Cu" "In16.Cu"
			)
			(hatch none 0.5)
			(connect_pads
				(clearance 0)
			)
			(min_thickness 0.25)
			(keepout
				(tracks not_allowed)
				(vias allowed)
				(pads allowed)
				(copperpour not_allowed)
				(footprints allowed)
			)
			(placement
				(enabled no)
				(sheetname "")
			)
			(fill
				(thermal_gap 0.5)
				(thermal_bridge_width 0.5)
				(island_removal_mode 0)
			)
			(polygon
				(pts
					(arc
						(start 115.644422 -431.360072)
						(mid 108.405422 -431.360072)
						(end 115.644422 -431.360072)
					)
				)
			)
		)
	)
	(footprint ""
		(layer "F.Cu")
		(at 443.89294 -77.496924)
		(property "Reference" "C61"
			(at 0 0 0)
			(layer "F.SilkS")
			(hide yes)
			(effects
				(font
					(size 1.27 1.27)
				)
			)
		)
		(property "Value" ""
			(at 0 0 0)
			(layer "F.Fab")
			(effects
				(font
					(size 1.27 1.27)
				)
			)
		)
		(duplicate_pad_numbers_are_jumpers no)
		(fp_line
			(start -0.7874 -0.4064)
			(end 0.7874 -0.4064)
			(stroke
				(width 0.1524)
				(type default)
			)
			(layer "F.SilkS")
		)
		(fp_line
			(start -0.7874 0.4064)
			(end -0.7874 -0.4064)
			(stroke
				(width 0.1524)
				(type default)
			)
			(layer "F.SilkS")
		)
		(fp_line
			(start 0.7874 -0.4064)
			(end 0.7874 0.4064)
			(stroke
				(width 0.1524)
				(type default)
			)
			(layer "F.SilkS")
		)
		(fp_line
			(start 0.7874 0.4064)
			(end -0.7874 0.4064)
			(stroke
				(width 0.1524)
				(type default)
			)
			(layer "F.SilkS")
		)
		(fp_line
			(start -0.67945 -0.305054)
			(end -0.12065 -0.305054)
			(stroke
				(width 0.1)
				(type default)
			)
			(layer "F.Fab")
		)
		(fp_line
			(start -0.67945 0.3048)
			(end -0.67945 -0.305054)
			(stroke
				(width 0.1)
				(type default)
			)
			(layer "F.Fab")
		)
		(fp_line
			(start -0.12065 -0.305054)
			(end -0.12065 -0.2794)
			(stroke
				(width 0.1)
				(type default)
			)
			(layer "F.Fab")
		)
		(fp_line
			(start -0.12065 -0.2794)
			(end 0.12065 -0.2794)
			(stroke
				(width 0.1)
				(type default)
			)
			(layer "F.Fab")
		)
		(fp_line
			(start -0.12065 0.2794)
			(end -0.12065 0.3048)
			(stroke
				(width 0.1)
				(type default)
			)
			(layer "F.Fab")
		)
		(fp_line
			(start -0.12065 0.3048)
			(end -0.67945 0.3048)
			(stroke
				(width 0.1)
				(type default)
			)
			(layer "F.Fab")
		)
		(fp_line
			(start 0.120396 0.2794)
			(end -0.12065 0.2794)
			(stroke
				(width 0.1)
				(type default)
			)
			(layer "F.Fab")
		)
		(fp_line
			(start 0.120396 0.3048)
			(end 0.120396 0.2794)
			(stroke
				(width 0.1)
				(type default)
			)
			(layer "F.Fab")
		)
		(fp_line
			(start 0.12065 -0.3048)
			(end 0.67945 -0.3048)
			(stroke
				(width 0.1)
				(type default)
			)
			(layer "F.Fab")
		)
		(fp_line
			(start 0.12065 -0.2794)
			(end 0.12065 -0.3048)
			(stroke
				(width 0.1)
				(type default)
			)
			(layer "F.Fab")
		)
		(fp_line
			(start 0.67945 -0.3048)
			(end 0.67945 0.3048)
			(stroke
				(width 0.1)
				(type default)
			)
			(layer "F.Fab")
		)
		(fp_line
			(start 0.67945 0.3048)
			(end 0.120396 0.3048)
			(stroke
				(width 0.1)
				(type default)
			)
			(layer "F.Fab")
		)
		(pad "1" smd circle
			(at -0.40005 0)
			(size 0 0)
			(layers "F.Cu" "F.Mask" "F.Paste")
			(net "P3V3")
		)
		(pad "2" smd circle
			(at 0.40005 0)
			(size 0 0)
			(layers "F.Cu" "F.Mask" "F.Paste")
			(net "GND")
		)
	)
)
